(kicad_pcb
	(version 20260206)
	(generator "pcbnew")
	(generator_version "10.0")
	(general
		(thickness 1.6)
		(legacy_teardrops no)
	)
	(paper "A4")
	(title_block
		(title "pdpb — Lightning_PDPB_BRD.brd")
		(comment 1 "Lightning (Wiwynn / Facebook NVMe JBOF) / footprints 635-642 of 1140")
	)
	(layers
		(0 "F.Cu" signal "TOP")
		(4 "In1.Cu" signal "L2GND")
		(6 "In2.Cu" signal "L3")
		(8 "In3.Cu" signal "L4VCC")
		(10 "In4.Cu" signal "L5VCC")
		(12 "In5.Cu" signal "L6")
		(14 "In6.Cu" signal "L7GND")
		(2 "B.Cu" signal "BOTTOM")
		(9 "F.Adhes" user "F.Adhesive")
		(11 "B.Adhes" user "B.Adhesive")
		(13 "F.Paste" user "Package Geometry/Pastemask Top")
		(15 "B.Paste" user "Package Geometry/Pastemask Bottom")
		(5 "F.SilkS" user "Ref Des/Silkscreen Top")
		(7 "B.SilkS" user "Ref Des/Silkscreen Bottom")
		(1 "F.Mask" user "Board Geometry/Soldermask Top")
		(3 "B.Mask" user "Board Geometry/Soldermask Bottom")
		(17 "Dwgs.User" user "User.Drawings")
		(19 "Cmts.User" user "User.Comments")
		(21 "Eco1.User" user "User.Eco1")
		(23 "Eco2.User" user "User.Eco2")
		(25 "Edge.Cuts" user "Board Geometry/Outline")
		(27 "Margin" user)
		(31 "F.CrtYd" user "Package Geometry/Place Bound Top")
		(29 "B.CrtYd" user "Package Geometry/Place Bound Bottom")
		(35 "F.Fab" user "Ref Des/Assembly Top")
		(33 "B.Fab" user "Ref Des/Assembly Bottom")
	)
	(footprint ""
		(layer "F.Cu")
		(at 37.5666 -417.3474 90)
		(property "Reference" "R148"
			(at 0 0 90)
			(layer "F.SilkS")
			(hide yes)
			(effects
				(font
					(size 1.27 1.27)
				)
			)
		)
		(property "Value" "4K7R2J-2-GP"
			(at 0.064008 -3.993896 90)
			(unlocked yes)
			(layer "F.Fab")
			(hide yes)
			(effects
				(font
					(size 1.016 1.016)
					(thickness 0.1524)
				)
			)
		)
		(property "Device Type" "R402H16"
			(at 0.064008 -5.517896 90)
			(unlocked yes)
			(layer "F.Fab")
			(hide yes)
			(effects
				(font
					(size 1.016 1.016)
					(thickness 0.1524)
				)
			)
		)
		(duplicate_pad_numbers_are_jumpers no)
		(fp_line
			(start 0.508 -0.9398)
			(end -0.508 -0.9398)
			(stroke
				(width 0.1524)
				(type default)
			)
			(layer "F.SilkS")
		)
		(fp_line
			(start -0.508 -0.9398)
			(end -0.508 0.9398)
			(stroke
				(width 0.1524)
				(type default)
			)
			(layer "F.SilkS")
		)
		(fp_rect
			(start -0.508 0.9398)
			(end 0.508 -0.9398)
			(stroke
				(width 0)
				(type default)
			)
			(fill no)
			(layer "F.CrtYd")
		)
		(fp_rect
			(start -0.508 0.9398)
			(end 0.508 -0.9398)
			(stroke
				(width 0)
				(type default)
			)
			(fill no)
			(layer "F.Fab")
		)
		(pad "1" smd custom
			(at 0 -0.4445 90)
			(size 0.1397 0.1397)
			(layers "F.Cu" "F.Mask" "F.Paste")
			(net "P12V")
			(options
				(clearance outline)
				(anchor circle)
			)
			(primitives
				(gr_poly
					(pts
						(arc
							(start -0.1778 -0.2794)
							(mid -0.249642 -0.249642)
							(end -0.2794 -0.1778)
						)
						(arc
							(start -0.2794 0.1778)
							(mid -0.249642 0.249642)
							(end -0.1778 0.2794)
						)
						(arc
							(start 0.1778 0.2794)
							(mid 0.249642 0.249642)
							(end 0.2794 0.1778)
						)
						(arc
							(start 0.2794 -0.1778)
							(mid 0.249642 -0.249642)
							(end 0.1778 -0.2794)
						)
					)
					(width 0)
					(fill yes)
				)
			)
		)
		(pad "2" smd custom
			(at 0 0.4445 90)
			(size 0.1397 0.1397)
			(layers "F.Cu" "F.Mask" "F.Paste")
			(net "SW_SSD10_R")
			(options
				(clearance outline)
				(anchor circle)
			)
			(primitives
				(gr_poly
					(pts
						(arc
							(start -0.1778 -0.2794)
							(mid -0.249642 -0.249642)
							(end -0.2794 -0.1778)
						)
						(arc
							(start -0.2794 0.1778)
							(mid -0.249642 0.249642)
							(end -0.1778 0.2794)
						)
						(arc
							(start 0.1778 0.2794)
							(mid 0.249642 0.249642)
							(end 0.2794 0.1778)
						)
						(arc
							(start 0.2794 -0.1778)
							(mid 0.249642 -0.249642)
							(end 0.1778 -0.2794)
						)
					)
					(width 0)
					(fill yes)
				)
			)
		)
	)
	(footprint ""
		(layer "F.Cu")
		(at 10.4394 -412.5976)
		(property "Reference" "R579"
			(at 0 0 0)
			(layer "F.SilkS")
			(hide yes)
			(effects
				(font
					(size 1.27 1.27)
				)
			)
		)
		(property "Value" "2R2010J-1-GP"
			(at 0.254 -8.0772 0)
			(unlocked yes)
			(layer "F.Fab")
			(hide yes)
			(effects
				(font
					(size 1.016 1.016)
					(thickness 0.1524)
				)
			)
		)
		(property "Device Type" "R2010H28"
			(at 0.254 -9.6774 0)
			(unlocked yes)
			(layer "F.Fab")
			(hide yes)
			(effects
				(font
					(size 1.016 1.016)
					(thickness 0.1524)
				)
			)
		)
		(duplicate_pad_numbers_are_jumpers no)
		(fp_line
			(start -1.651 -3.302)
			(end -1.651 3.302)
			(stroke
				(width 0.1524)
				(type default)
			)
			(layer "F.SilkS")
		)
		(fp_line
			(start -1.651 3.302)
			(end 1.651 3.302)
			(stroke
				(width 0.1524)
				(type default)
			)
			(layer "F.SilkS")
		)
		(fp_line
			(start 1.651 -3.302)
			(end -1.651 -3.302)
			(stroke
				(width 0.1524)
				(type default)
			)
			(layer "F.SilkS")
		)
		(fp_line
			(start 1.651 3.302)
			(end 1.651 -3.302)
			(stroke
				(width 0.1524)
				(type default)
			)
			(layer "F.SilkS")
		)
		(fp_rect
			(start -1.7272 -3.3782)
			(end 1.7272 3.3782)
			(stroke
				(width 0)
				(type default)
			)
			(fill no)
			(layer "F.CrtYd")
		)
		(fp_poly
			(pts
				(xy 1.7272 3.3782) (xy 1.7272 -3.3782) (xy -1.7272 -3.3782) (xy -1.7272 3.3782)
			)
			(stroke
				(width 0)
				(type default)
			)
			(fill no)
			(layer "F.Fab")
		)
		(pad "1" smd rect
			(at 0 -2.3495)
			(size 2.794 1.143)
			(layers "F.Cu" "F.Mask" "F.Paste")
			(net "PCIE_MATED#_A")
		)
		(pad "2" smd rect
			(at 0 2.3495)
			(size 2.794 1.143)
			(layers "F.Cu" "F.Mask" "F.Paste")
			(net "GND")
		)
	)
	(footprint ""
		(layer "F.Cu")
		(at 35.941 -301.2186 -90)
		(property "Reference" "R9826"
			(at 0 0 270)
			(layer "F.SilkS")
			(hide yes)
			(effects
				(font
					(size 1.27 1.27)
				)
			)
		)
		(property "Value" "2K2R5F-GP"
			(at 0 -8.9535 270)
			(unlocked yes)
			(layer "F.Fab")
			(hide yes)
			(effects
				(font
					(size 1.27 1.016)
					(thickness 0.1524)
				)
			)
		)
		(property "Device Type" "R805H24"
			(at 0 -10.6299 270)
			(unlocked yes)
			(layer "F.Fab")
			(hide yes)
			(effects
				(font
					(size 1.27 1.016)
					(thickness 0.1524)
				)
			)
		)
		(duplicate_pad_numbers_are_jumpers no)
		(fp_line
			(start -0.889 1.7018)
			(end 0.889 1.7018)
			(stroke
				(width 0.1524)
				(type default)
			)
			(layer "F.SilkS")
		)
		(fp_line
			(start 0.889 1.7018)
			(end 0.889 -0.508)
			(stroke
				(width 0.1524)
				(type default)
			)
			(layer "F.SilkS")
		)
		(fp_line
			(start -0.889 0.0762)
			(end -0.889 1.7018)
			(stroke
				(width 0.1524)
				(type default)
			)
			(layer "F.SilkS")
		)
		(fp_line
			(start -0.889 -1.7018)
			(end -0.889 0.2794)
			(stroke
				(width 0.1524)
				(type default)
			)
			(layer "F.SilkS")
		)
		(fp_line
			(start 0.889 -1.7018)
			(end 0.889 -0.381)
			(stroke
				(width 0.1524)
				(type default)
			)
			(layer "F.SilkS")
		)
		(fp_line
			(start 0.889 -1.7018)
			(end -0.889 -1.7018)
			(stroke
				(width 0.1524)
				(type default)
			)
			(layer "F.SilkS")
		)
		(fp_poly
			(pts
				(xy 0.9652 -1.778) (xy 0.9652 1.778) (xy -0.9652 1.778) (xy -0.9652 -1.778)
			)
			(stroke
				(width 0)
				(type default)
			)
			(fill no)
			(layer "F.CrtYd")
		)
		(fp_rect
			(start -0.9652 1.778)
			(end 0.9652 -1.778)
			(stroke
				(width 0)
				(type default)
			)
			(fill no)
			(layer "F.Fab")
		)
		(pad "1" smd rect
			(at 0 -0.9652 270)
			(size 1.397 1.143)
			(layers "F.Cu" "F.Mask" "F.Paste")
			(net "P12V_SSD7")
		)
		(pad "2" smd rect
			(at 0 0.9652 270)
			(size 1.397 1.143)
			(layers "F.Cu" "F.Mask" "F.Paste")
			(net "P12V_MOST7_GATE_D")
		)
	)
	(footprint ""
		(layer "F.Cu")
		(at 107.442 -307.848 -90)
		(property "Reference" "R9452"
			(at 0 0 270)
			(layer "F.SilkS")
			(hide yes)
			(effects
				(font
					(size 1.27 1.27)
				)
			)
		)
		(property "Value" "10R2F-L-GP"
			(at 0.064008 -3.993896 270)
			(unlocked yes)
			(layer "F.Fab")
			(hide yes)
			(effects
				(font
					(size 1.016 1.016)
					(thickness 0.1524)
				)
			)
		)
		(property "Device Type" "R402H14"
			(at 0.064008 -5.517896 270)
			(unlocked yes)
			(layer "F.Fab")
			(hide yes)
			(effects
				(font
					(size 1.016 1.016)
					(thickness 0.1524)
				)
			)
		)
		(duplicate_pad_numbers_are_jumpers no)
		(fp_line
			(start -0.508 -0.9398)
			(end -0.508 0.9398)
			(stroke
				(width 0.1524)
				(type default)
			)
			(layer "F.SilkS")
		)
		(fp_line
			(start 0.508 -0.9398)
			(end -0.508 -0.9398)
			(stroke
				(width 0.1524)
				(type default)
			)
			(layer "F.SilkS")
		)
		(fp_rect
			(start -0.508 0.9398)
			(end 0.508 -0.9398)
			(stroke
				(width 0)
				(type default)
			)
			(fill no)
			(layer "F.CrtYd")
		)
		(fp_rect
			(start -0.508 0.9398)
			(end 0.508 -0.9398)
			(stroke
				(width 0)
				(type default)
			)
			(fill no)
			(layer "F.Fab")
		)
		(pad "1" smd custom
			(at 0 -0.4445 270)
			(size 0.1397 0.1397)
			(layers "F.Cu" "F.Mask" "F.Paste")
			(net "SSD_PRSNT_NET1")
			(options
				(clearance outline)
				(anchor circle)
			)
			(primitives
				(gr_poly
					(pts
						(arc
							(start -0.1778 -0.2794)
							(mid -0.249642 -0.249642)
							(end -0.2794 -0.1778)
						)
						(arc
							(start -0.2794 0.1778)
							(mid -0.249642 0.249642)
							(end -0.1778 0.2794)
						)
						(arc
							(start 0.1778 0.2794)
							(mid 0.249642 0.249642)
							(end 0.2794 0.1778)
						)
						(arc
							(start 0.2794 -0.1778)
							(mid 0.249642 -0.249642)
							(end 0.1778 -0.2794)
						)
					)
					(width 0)
					(fill yes)
				)
			)
		)
		(pad "2" smd custom
			(at 0 0.4445 270)
			(size 0.1397 0.1397)
			(layers "F.Cu" "F.Mask" "F.Paste")
			(net "SSD_PRSNT1")
			(options
				(clearance outline)
				(anchor circle)
			)
			(primitives
				(gr_poly
					(pts
						(arc
							(start -0.1778 -0.2794)
							(mid -0.249642 -0.249642)
							(end -0.2794 -0.1778)
						)
						(arc
							(start -0.2794 0.1778)
							(mid -0.249642 0.249642)
							(end -0.1778 0.2794)
						)
						(arc
							(start 0.1778 0.2794)
							(mid 0.249642 0.249642)
							(end 0.2794 0.1778)
						)
						(arc
							(start 0.2794 -0.1778)
							(mid 0.249642 -0.249642)
							(end 0.1778 -0.2794)
						)
					)
					(width 0)
					(fill yes)
				)
			)
		)
	)
	(footprint ""
		(layer "F.Cu")
		(at 208.534 -94.234)
		(property "Reference" "R9764"
			(at 0 0 0)
			(layer "F.SilkS")
			(hide yes)
			(effects
				(font
					(size 1.27 1.27)
				)
			)
		)
		(property "Value" "4K7R2J-2-GP"
			(at 0.064008 -3.993896 0)
			(unlocked yes)
			(layer "F.Fab")
			(hide yes)
			(effects
				(font
					(size 1.016 1.016)
					(thickness 0.1524)
				)
			)
		)
		(property "Device Type" "R402H16"
			(at 0.064008 -5.517896 0)
			(unlocked yes)
			(layer "F.Fab")
			(hide yes)
			(effects
				(font
					(size 1.016 1.016)
					(thickness 0.1524)
				)
			)
		)
		(duplicate_pad_numbers_are_jumpers no)
		(fp_line
			(start -0.508 -0.9398)
			(end -0.508 0.9398)
			(stroke
				(width 0.1524)
				(type default)
			)
			(layer "F.SilkS")
		)
		(fp_line
			(start 0.508 -0.9398)
			(end -0.508 -0.9398)
			(stroke
				(width 0.1524)
				(type default)
			)
			(layer "F.SilkS")
		)
		(fp_rect
			(start -0.508 0.9398)
			(end 0.508 -0.9398)
			(stroke
				(width 0)
				(type default)
			)
			(fill no)
			(layer "F.CrtYd")
		)
		(fp_rect
			(start -0.508 0.9398)
			(end 0.508 -0.9398)
			(stroke
				(width 0)
				(type default)
			)
			(fill no)
			(layer "F.Fab")
		)
		(pad "1" smd custom
			(at 0 -0.4445)
			(size 0.1397 0.1397)
			(layers "F.Cu" "F.Mask" "F.Paste")
			(net "SSD4_PWREN")
			(options
				(clearance outline)
				(anchor circle)
			)
			(primitives
				(gr_poly
					(pts
						(arc
							(start -0.1778 -0.2794)
							(mid -0.249642 -0.249642)
							(end -0.2794 -0.1778)
						)
						(arc
							(start -0.2794 0.1778)
							(mid -0.249642 0.249642)
							(end -0.1778 0.2794)
						)
						(arc
							(start 0.1778 0.2794)
							(mid 0.249642 0.249642)
							(end 0.2794 0.1778)
						)
						(arc
							(start 0.2794 -0.1778)
							(mid 0.249642 -0.249642)
							(end 0.1778 -0.2794)
						)
					)
					(width 0)
					(fill yes)
				)
			)
		)
		(pad "2" smd custom
			(at 0 0.4445)
			(size 0.1397 0.1397)
			(layers "F.Cu" "F.Mask" "F.Paste")
			(net "GND")
			(options
				(clearance outline)
				(anchor circle)
			)
			(primitives
				(gr_poly
					(pts
						(arc
							(start -0.1778 -0.2794)
							(mid -0.249642 -0.249642)
							(end -0.2794 -0.1778)
						)
						(arc
							(start -0.2794 0.1778)
							(mid -0.249642 0.249642)
							(end -0.1778 0.2794)
						)
						(arc
							(start 0.1778 0.2794)
							(mid 0.249642 0.249642)
							(end 0.2794 0.1778)
						)
						(arc
							(start 0.2794 -0.1778)
							(mid 0.249642 -0.249642)
							(end 0.1778 -0.2794)
						)
					)
					(width 0)
					(fill yes)
				)
			)
		)
	)
	(footprint ""
		(layer "F.Cu")
		(at 206.502 -89.535)
		(property "Reference" "D22"
			(at 0 0 0)
			(layer "F.SilkS")
			(hide yes)
			(effects
				(font
					(size 1.27 1.27)
				)
			)
		)
		(property "Value" "RB551V30-1-GP"
			(at 0 -6.7818 0)
			(unlocked yes)
			(layer "F.Fab")
			(hide yes)
			(effects
				(font
					(size 1.016 1.016)
					(thickness 0.1524)
				)
			)
		)
		(property "Device Type" "SOD323AKH44"
			(at 0 -8.6868 0)
			(unlocked yes)
			(layer "F.Fab")
			(hide yes)
			(effects
				(font
					(size 1.016 1.016)
					(thickness 0.1524)
				)
			)
		)
		(duplicate_pad_numbers_are_jumpers no)
		(fp_line
			(start -0.889 -1.9304)
			(end 0.889 -1.9304)
			(stroke
				(width 0.1524)
				(type default)
			)
			(layer "F.SilkS")
		)
		(fp_line
			(start -0.889 2.159)
			(end -0.889 -1.9304)
			(stroke
				(width 0.1524)
				(type default)
			)
			(layer "F.SilkS")
		)
		(fp_line
			(start 0.762 2.0574)
			(end -0.762 2.0574)
			(stroke
				(width 0.508)
				(type default)
			)
			(layer "F.SilkS")
		)
		(fp_line
			(start 0.889 -1.9304)
			(end 0.889 2.159)
			(stroke
				(width 0.1524)
				(type default)
			)
			(layer "F.SilkS")
		)
		(fp_line
			(start 0.889 2.159)
			(end -0.889 2.159)
			(stroke
				(width 0.1524)
				(type default)
			)
			(layer "F.SilkS")
		)
		(fp_rect
			(start -1.016 2.3114)
			(end 1.016 -2.0066)
			(stroke
				(width 0)
				(type default)
			)
			(fill no)
			(layer "F.CrtYd")
		)
		(fp_poly
			(pts
				(xy -1.016 -2.0066) (xy 1.016 -2.0066) (xy 1.016 2.3114) (xy -1.016 2.3114)
			)
			(stroke
				(width 0)
				(type default)
			)
			(fill no)
			(layer "F.Fab")
		)
		(pad "A" smd rect
			(at 0 -1.143)
			(size 0.5588 1.016)
			(layers "F.Cu" "F.Mask" "F.Paste")
			(net "SW_SSD4_R")
		)
		(pad "K" smd rect
			(at 0 1.143)
			(size 0.5588 1.016)
			(layers "F.Cu" "F.Mask" "F.Paste")
			(net "SW_SSD4_N")
		)
	)
	(footprint ""
		(layer "F.Cu")
		(at 219.9894 -189.4332)
		(property "Reference" "PC1226"
			(at 0 0 0)
			(layer "F.SilkS")
			(hide yes)
			(effects
				(font
					(size 1.27 1.27)
				)
			)
		)
		(property "Value" "SC22U25V6KX-GP-U"
			(at -2.860802 -5.279644 0)
			(unlocked yes)
			(layer "F.Fab")
			(hide yes)
			(effects
				(font
					(size 1.016 1.016)
					(thickness 0.1524)
				)
			)
		)
		(property "Device Type" "C1206-TO0D3H75"
			(at -2.860802 -6.803644 0)
			(unlocked yes)
			(layer "F.Fab")
			(hide yes)
			(effects
				(font
					(size 1.016 1.016)
					(thickness 0.1524)
				)
			)
		)
		(duplicate_pad_numbers_are_jumpers no)
		(fp_line
			(start -1.3081 -2.3749)
			(end 1.3081 -2.3749)
			(stroke
				(width 0.1524)
				(type default)
			)
			(layer "F.SilkS")
		)
		(fp_line
			(start -1.3081 2.3749)
			(end -1.3081 -2.3749)
			(stroke
				(width 0.1524)
				(type default)
			)
			(layer "F.SilkS")
		)
		(fp_line
			(start 1.3081 -2.3749)
			(end 1.3081 2.3749)
			(stroke
				(width 0.1524)
				(type default)
			)
			(layer "F.SilkS")
		)
		(fp_line
			(start 1.3081 2.3749)
			(end -1.3081 2.3749)
			(stroke
				(width 0.1524)
				(type default)
			)
			(layer "F.SilkS")
		)
		(fp_rect
			(start -0.8001 1.6002)
			(end 0.8001 -1.6002)
			(stroke
				(width 0)
				(type default)
			)
			(fill no)
			(layer "F.CrtYd")
		)
		(fp_poly
			(pts
				(xy -1.5621 2.4511) (xy -1.5621 1.6002) (xy 0.8001 1.6002) (xy 0.8001 -1.6002) (xy -0.8001 -1.6002)
				(xy -0.8001 1.5875) (xy -1.5621 1.5875) (xy -1.5621 -2.4511) (xy 1.5621 -2.4511) (xy 1.5621 2.4511)
			)
			(stroke
				(width 0)
				(type default)
			)
			(fill no)
			(layer "F.CrtYd")
		)
		(fp_rect
			(start -1.5621 2.4511)
			(end 1.5621 -2.4511)
			(stroke
				(width 0)
				(type default)
			)
			(fill no)
			(layer "F.Fab")
		)
		(pad "1" smd rect
			(at 0 -1.392936)
			(size 2.1082 1.4478)
			(layers "F.Cu" "F.Mask" "F.Paste")
			(net "P12V_SSD3")
		)
		(pad "2" smd rect
			(at 0 1.392936)
			(size 2.1082 1.4478)
			(layers "F.Cu" "F.Mask" "F.Paste")
			(net "GND")
		)
	)
	(footprint ""
		(layer "F.Cu")
		(at 39.116 -205.74)
		(property "Reference" "R9753"
			(at 0 0 0)
			(layer "F.SilkS")
			(hide yes)
			(effects
				(font
					(size 1.27 1.27)
				)
			)
		)
		(property "Value" "4K7R2J-2-GP"
			(at 0.064008 -3.993896 0)
			(unlocked yes)
			(layer "F.Fab")
			(hide yes)
			(effects
				(font
					(size 1.016 1.016)
					(thickness 0.1524)
				)
			)
		)
		(property "Device Type" "R402H16"
			(at 0.064008 -5.517896 0)
			(unlocked yes)
			(layer "F.Fab")
			(hide yes)
			(effects
				(font
					(size 1.016 1.016)
					(thickness 0.1524)
				)
			)
		)
		(duplicate_pad_numbers_are_jumpers no)
		(fp_line
			(start -0.508 -0.9398)
			(end -0.508 0.9398)
			(stroke
				(width 0.1524)
				(type default)
			)
			(layer "F.SilkS")
		)
		(fp_line
			(start 0.508 -0.9398)
			(end -0.508 -0.9398)
			(stroke
				(width 0.1524)
				(type default)
			)
			(layer "F.SilkS")
		)
		(fp_rect
			(start -0.508 0.9398)
			(end 0.508 -0.9398)
			(stroke
				(width 0)
				(type default)
			)
			(fill no)
			(layer "F.CrtYd")
		)
		(fp_rect
			(start -0.508 0.9398)
			(end 0.508 -0.9398)
			(stroke
				(width 0)
				(type default)
			)
			(fill no)
			(layer "F.Fab")
		)
		(pad "1" smd custom
			(at 0 -0.4445)
			(size 0.1397 0.1397)
			(layers "F.Cu" "F.Mask" "F.Paste")
			(net "P3V3")
			(options
				(clearance outline)
				(anchor circle)
			)
			(primitives
				(gr_poly
					(pts
						(arc
							(start -0.1778 -0.2794)
							(mid -0.249642 -0.249642)
							(end -0.2794 -0.1778)
						)
						(arc
							(start -0.2794 0.1778)
							(mid -0.249642 0.249642)
							(end -0.1778 0.2794)
						)
						(arc
							(start 0.1778 0.2794)
							(mid 0.249642 0.249642)
							(end 0.2794 0.1778)
						)
						(arc
							(start 0.2794 -0.1778)
							(mid 0.249642 -0.249642)
							(end 0.1778 -0.2794)
						)
					)
					(width 0)
					(fill yes)
				)
			)
		)
		(pad "2" smd custom
			(at 0 0.4445)
			(size 0.1397 0.1397)
			(layers "F.Cu" "F.Mask" "F.Paste")
			(net "SSD12_PWREN")
			(options
				(clearance outline)
				(anchor circle)
			)
			(primitives
				(gr_poly
					(pts
						(arc
							(start -0.1778 -0.2794)
							(mid -0.249642 -0.249642)
							(end -0.2794 -0.1778)
						)
						(arc
							(start -0.2794 0.1778)
							(mid -0.249642 0.249642)
							(end -0.1778 0.2794)
						)
						(arc
							(start 0.1778 0.2794)
							(mid 0.249642 0.249642)
							(end 0.2794 0.1778)
						)
						(arc
							(start 0.2794 -0.1778)
							(mid 0.249642 -0.249642)
							(end 0.1778 -0.2794)
						)
					)
					(width 0)
					(fill yes)
				)
			)
		)
	)
)
